(kicad_pcb
	(version 20260206)
	(generator "pcbnew")
	(generator_version "10.0")
	(general
		(thickness 1.6)
		(legacy_teardrops no)
	)
	(paper "A4")
	(title_block
		(title "04192023_DAF0TMB3IC0_F0TG_MB_C_brd_V02_OCP.brd")
		(comment 1 "Grand Teton / footprints 6082-6088 of 8354")
	)
	(layers
		(0 "F.Cu" signal "TOP")
		(4 "In1.Cu" signal "GND")
		(6 "In2.Cu" signal "IN1")
		(8 "In3.Cu" signal "GND1")
		(10 "In4.Cu" signal "IN2")
		(12 "In5.Cu" signal "GND2")
		(14 "In6.Cu" signal "IN3")
		(16 "In7.Cu" signal "GND3")
		(18 "In8.Cu" signal "VCC")
		(20 "In9.Cu" signal "VCC1")
		(22 "In10.Cu" signal "GND4")
		(24 "In11.Cu" signal "IN4")
		(26 "In12.Cu" signal "GND5")
		(28 "In13.Cu" signal "IN5")
		(30 "In14.Cu" signal "GND6")
		(32 "In15.Cu" signal "IN6")
		(34 "In16.Cu" signal "GND7")
		(2 "B.Cu" signal "BOTTOM")
		(9 "F.Adhes" user "F.Adhesive")
		(11 "B.Adhes" user "B.Adhesive")
		(13 "F.Paste" user "Package Geometry/Pastemask Top")
		(15 "B.Paste" user "Package Geometry/Pastemask Bottom")
		(5 "F.SilkS" user "Ref Des/Silkscreen Top")
		(7 "B.SilkS" user "Ref Des/Silkscreen Bottom")
		(1 "F.Mask" user "Board Geometry/Soldermask Top")
		(3 "B.Mask" user "Board Geometry/Soldermask Bottom")
		(17 "Dwgs.User" user "User.Drawings")
		(19 "Cmts.User" user "User.Comments")
		(21 "Eco1.User" user "User.Eco1")
		(23 "Eco2.User" user "User.Eco2")
		(25 "Edge.Cuts" user "Board Geometry/Outline")
		(27 "Margin" user)
		(31 "F.CrtYd" user "Package Geometry/Place Bound Top")
		(29 "B.CrtYd" user "Package Geometry/Place Bound Bottom")
		(35 "F.Fab" user "Ref Des/Assembly Top")
		(33 "B.Fab" user "Ref Des/Assembly Bottom")
	)
	(footprint ""
		(layer "B.Cu")
		(at 338.318856 -398.942052 90)
		(property "Reference" "C638"
			(at 0 0 90)
			(layer "B.SilkS")
			(hide yes)
			(effects
				(font
					(size 1.27 1.27)
				)
				(justify mirror)
			)
		)
		(property "Value" ""
			(at 0 0 90)
			(layer "B.Fab")
			(effects
				(font
					(size 1.27 1.27)
				)
				(justify mirror)
			)
		)
		(duplicate_pad_numbers_are_jumpers no)
		(fp_line
			(start 0.7874 -0.4064)
			(end -0.7874 -0.4064)
			(stroke
				(width 0.1524)
				(type default)
			)
			(layer "B.SilkS")
		)
		(fp_line
			(start -0.7874 -0.4064)
			(end -0.7874 0.4064)
			(stroke
				(width 0.1524)
				(type default)
			)
			(layer "B.SilkS")
		)
		(fp_line
			(start 0.7874 0.4064)
			(end 0.7874 -0.4064)
			(stroke
				(width 0.1524)
				(type default)
			)
			(layer "B.SilkS")
		)
		(fp_line
			(start -0.7874 0.4064)
			(end 0.7874 0.4064)
			(stroke
				(width 0.1524)
				(type default)
			)
			(layer "B.SilkS")
		)
		(fp_line
			(start 0.67945 -0.305054)
			(end 0.12065 -0.305054)
			(stroke
				(width 0.1)
				(type default)
			)
			(layer "B.Fab")
		)
		(fp_line
			(start 0.12065 -0.305054)
			(end 0.12065 -0.2794)
			(stroke
				(width 0.1)
				(type default)
			)
			(layer "B.Fab")
		)
		(fp_line
			(start -0.12065 -0.3048)
			(end -0.67945 -0.3048)
			(stroke
				(width 0.1)
				(type default)
			)
			(layer "B.Fab")
		)
		(fp_line
			(start -0.67945 -0.3048)
			(end -0.67945 0.3048)
			(stroke
				(width 0.1)
				(type default)
			)
			(layer "B.Fab")
		)
		(fp_line
			(start 0.12065 -0.2794)
			(end -0.12065 -0.2794)
			(stroke
				(width 0.1)
				(type default)
			)
			(layer "B.Fab")
		)
		(fp_line
			(start -0.12065 -0.2794)
			(end -0.12065 -0.3048)
			(stroke
				(width 0.1)
				(type default)
			)
			(layer "B.Fab")
		)
		(fp_line
			(start 0.12065 0.2794)
			(end 0.12065 0.3048)
			(stroke
				(width 0.1)
				(type default)
			)
			(layer "B.Fab")
		)
		(fp_line
			(start -0.120396 0.2794)
			(end 0.12065 0.2794)
			(stroke
				(width 0.1)
				(type default)
			)
			(layer "B.Fab")
		)
		(fp_line
			(start 0.67945 0.3048)
			(end 0.67945 -0.305054)
			(stroke
				(width 0.1)
				(type default)
			)
			(layer "B.Fab")
		)
		(fp_line
			(start 0.12065 0.3048)
			(end 0.67945 0.3048)
			(stroke
				(width 0.1)
				(type default)
			)
			(layer "B.Fab")
		)
		(fp_line
			(start -0.120396 0.3048)
			(end -0.120396 0.2794)
			(stroke
				(width 0.1)
				(type default)
			)
			(layer "B.Fab")
		)
		(fp_line
			(start -0.67945 0.3048)
			(end -0.120396 0.3048)
			(stroke
				(width 0.1)
				(type default)
			)
			(layer "B.Fab")
		)
		(pad "1" smd circle
			(at 0.40005 0 270)
			(size 0 0)
			(layers "B.Cu" "B.Mask" "B.Paste")
			(net "P0V9_CPU0_RT1_2A")
		)
		(pad "2" smd circle
			(at -0.40005 0 270)
			(size 0 0)
			(layers "B.Cu" "B.Mask" "B.Paste")
			(net "GND")
		)
	)
	(footprint ""
		(layer "B.Cu")
		(at 121.706386 -252.543564)
		(property "Reference" "C2468"
			(at 0 0 0)
			(layer "B.SilkS")
			(hide yes)
			(effects
				(font
					(size 1.27 1.27)
				)
				(justify mirror)
			)
		)
		(property "Value" ""
			(at 0 0 0)
			(layer "B.Fab")
			(effects
				(font
					(size 1.27 1.27)
				)
				(justify mirror)
			)
		)
		(duplicate_pad_numbers_are_jumpers no)
		(fp_line
			(start -0.7874 -0.4064)
			(end -0.7874 0.4064)
			(stroke
				(width 0.1524)
				(type default)
			)
			(layer "B.SilkS")
		)
		(fp_line
			(start -0.7874 0.4064)
			(end 0.7874 0.4064)
			(stroke
				(width 0.1524)
				(type default)
			)
			(layer "B.SilkS")
		)
		(fp_line
			(start 0.7874 -0.4064)
			(end -0.7874 -0.4064)
			(stroke
				(width 0.1524)
				(type default)
			)
			(layer "B.SilkS")
		)
		(fp_line
			(start 0.7874 0.4064)
			(end 0.7874 -0.4064)
			(stroke
				(width 0.1524)
				(type default)
			)
			(layer "B.SilkS")
		)
		(fp_line
			(start -0.67945 -0.3048)
			(end -0.67945 0.3048)
			(stroke
				(width 0.1)
				(type default)
			)
			(layer "B.Fab")
		)
		(fp_line
			(start -0.67945 0.3048)
			(end -0.120396 0.3048)
			(stroke
				(width 0.1)
				(type default)
			)
			(layer "B.Fab")
		)
		(fp_line
			(start -0.12065 -0.3048)
			(end -0.67945 -0.3048)
			(stroke
				(width 0.1)
				(type default)
			)
			(layer "B.Fab")
		)
		(fp_line
			(start -0.12065 -0.2794)
			(end -0.12065 -0.3048)
			(stroke
				(width 0.1)
				(type default)
			)
			(layer "B.Fab")
		)
		(fp_line
			(start -0.120396 0.2794)
			(end 0.12065 0.2794)
			(stroke
				(width 0.1)
				(type default)
			)
			(layer "B.Fab")
		)
		(fp_line
			(start -0.120396 0.3048)
			(end -0.120396 0.2794)
			(stroke
				(width 0.1)
				(type default)
			)
			(layer "B.Fab")
		)
		(fp_line
			(start 0.12065 -0.305054)
			(end 0.12065 -0.2794)
			(stroke
				(width 0.1)
				(type default)
			)
			(layer "B.Fab")
		)
		(fp_line
			(start 0.12065 -0.2794)
			(end -0.12065 -0.2794)
			(stroke
				(width 0.1)
				(type default)
			)
			(layer "B.Fab")
		)
		(fp_line
			(start 0.12065 0.2794)
			(end 0.12065 0.3048)
			(stroke
				(width 0.1)
				(type default)
			)
			(layer "B.Fab")
		)
		(fp_line
			(start 0.12065 0.3048)
			(end 0.67945 0.3048)
			(stroke
				(width 0.1)
				(type default)
			)
			(layer "B.Fab")
		)
		(fp_line
			(start 0.67945 -0.305054)
			(end 0.12065 -0.305054)
			(stroke
				(width 0.1)
				(type default)
			)
			(layer "B.Fab")
		)
		(fp_line
			(start 0.67945 0.3048)
			(end 0.67945 -0.305054)
			(stroke
				(width 0.1)
				(type default)
			)
			(layer "B.Fab")
		)
		(pad "1" smd circle
			(at 0.40005 0 180)
			(size 0 0)
			(layers "B.Cu" "B.Mask" "B.Paste")
			(net "PVDDCR_SOC_P1")
		)
		(pad "2" smd circle
			(at -0.40005 0 180)
			(size 0 0)
			(layers "B.Cu" "B.Mask" "B.Paste")
			(net "GND")
		)
	)
	(footprint ""
		(layer "B.Cu")
		(at 373.329454 -259.729986)
		(property "Reference" "C2584"
			(at 0 0 0)
			(layer "B.SilkS")
			(hide yes)
			(effects
				(font
					(size 1.27 1.27)
				)
				(justify mirror)
			)
		)
		(property "Value" ""
			(at 0 0 0)
			(layer "B.Fab")
			(effects
				(font
					(size 1.27 1.27)
				)
				(justify mirror)
			)
		)
		(duplicate_pad_numbers_are_jumpers no)
		(fp_line
			(start -0.7874 -0.4064)
			(end -0.7874 0.4064)
			(stroke
				(width 0.1524)
				(type default)
			)
			(layer "B.SilkS")
		)
		(fp_line
			(start -0.7874 0.4064)
			(end 0.7874 0.4064)
			(stroke
				(width 0.1524)
				(type default)
			)
			(layer "B.SilkS")
		)
		(fp_line
			(start 0.7874 -0.4064)
			(end -0.7874 -0.4064)
			(stroke
				(width 0.1524)
				(type default)
			)
			(layer "B.SilkS")
		)
		(fp_line
			(start 0.7874 0.4064)
			(end 0.7874 -0.4064)
			(stroke
				(width 0.1524)
				(type default)
			)
			(layer "B.SilkS")
		)
		(fp_line
			(start -0.67945 -0.3048)
			(end -0.67945 0.3048)
			(stroke
				(width 0.1)
				(type default)
			)
			(layer "B.Fab")
		)
		(fp_line
			(start -0.67945 0.3048)
			(end -0.120396 0.3048)
			(stroke
				(width 0.1)
				(type default)
			)
			(layer "B.Fab")
		)
		(fp_line
			(start -0.12065 -0.3048)
			(end -0.67945 -0.3048)
			(stroke
				(width 0.1)
				(type default)
			)
			(layer "B.Fab")
		)
		(fp_line
			(start -0.12065 -0.2794)
			(end -0.12065 -0.3048)
			(stroke
				(width 0.1)
				(type default)
			)
			(layer "B.Fab")
		)
		(fp_line
			(start -0.120396 0.2794)
			(end 0.12065 0.2794)
			(stroke
				(width 0.1)
				(type default)
			)
			(layer "B.Fab")
		)
		(fp_line
			(start -0.120396 0.3048)
			(end -0.120396 0.2794)
			(stroke
				(width 0.1)
				(type default)
			)
			(layer "B.Fab")
		)
		(fp_line
			(start 0.12065 -0.305054)
			(end 0.12065 -0.2794)
			(stroke
				(width 0.1)
				(type default)
			)
			(layer "B.Fab")
		)
		(fp_line
			(start 0.12065 -0.2794)
			(end -0.12065 -0.2794)
			(stroke
				(width 0.1)
				(type default)
			)
			(layer "B.Fab")
		)
		(fp_line
			(start 0.12065 0.2794)
			(end 0.12065 0.3048)
			(stroke
				(width 0.1)
				(type default)
			)
			(layer "B.Fab")
		)
		(fp_line
			(start 0.12065 0.3048)
			(end 0.67945 0.3048)
			(stroke
				(width 0.1)
				(type default)
			)
			(layer "B.Fab")
		)
		(fp_line
			(start 0.67945 -0.305054)
			(end 0.12065 -0.305054)
			(stroke
				(width 0.1)
				(type default)
			)
			(layer "B.Fab")
		)
		(fp_line
			(start 0.67945 0.3048)
			(end 0.67945 -0.305054)
			(stroke
				(width 0.1)
				(type default)
			)
			(layer "B.Fab")
		)
		(pad "1" smd circle
			(at 0.40005 0 180)
			(size 0 0)
			(layers "B.Cu" "B.Mask" "B.Paste")
			(net "PVDDCR_SOC_P0")
		)
		(pad "2" smd circle
			(at -0.40005 0 180)
			(size 0 0)
			(layers "B.Cu" "B.Mask" "B.Paste")
			(net "GND")
		)
	)
	(footprint ""
		(layer "B.Cu")
		(at 403.17928 -178.77282 90)
		(property "Reference" "PC603_2"
			(at 0 0 90)
			(layer "B.SilkS")
			(hide yes)
			(effects
				(font
					(size 1.27 1.27)
				)
				(justify mirror)
			)
		)
		(property "Value" ""
			(at 0 0 90)
			(layer "B.Fab")
			(effects
				(font
					(size 1.27 1.27)
				)
				(justify mirror)
			)
		)
		(duplicate_pad_numbers_are_jumpers no)
		(fp_line
			(start 1.524 -0.762)
			(end -1.524 -0.762)
			(stroke
				(width 0.1524)
				(type default)
			)
			(layer "B.SilkS")
		)
		(fp_line
			(start -1.524 -0.762)
			(end -1.524 0.762)
			(stroke
				(width 0.1524)
				(type default)
			)
			(layer "B.SilkS")
		)
		(fp_line
			(start 1.524 0.762)
			(end 1.524 -0.762)
			(stroke
				(width 0.1524)
				(type default)
			)
			(layer "B.SilkS")
		)
		(fp_line
			(start -1.524 0.762)
			(end 1.524 0.762)
			(stroke
				(width 0.1524)
				(type default)
			)
			(layer "B.SilkS")
		)
		(fp_line
			(start 1.1049 -0.724916)
			(end 1.1049 0.724916)
			(stroke
				(width 0.1)
				(type default)
			)
			(layer "B.Fab")
		)
		(fp_line
			(start -1.1049 -0.724916)
			(end 1.1049 -0.724916)
			(stroke
				(width 0.1)
				(type default)
			)
			(layer "B.Fab")
		)
		(fp_line
			(start 1.1049 0.724916)
			(end -1.1049 0.724916)
			(stroke
				(width 0.1)
				(type default)
			)
			(layer "B.Fab")
		)
		(fp_line
			(start -1.1049 0.724916)
			(end -1.1049 -0.724916)
			(stroke
				(width 0.1)
				(type default)
			)
			(layer "B.Fab")
		)
		(pad "1" smd rect
			(at 0.889 0 90)
			(size 1.016 1.27)
			(layers "B.Cu" "B.Mask" "B.Paste")
			(net "PVDDCR_SOC_P0")
		)
		(pad "2" smd rect
			(at -0.889 0 90)
			(size 1.016 1.27)
			(layers "B.Cu" "B.Mask" "B.Paste")
			(net "GND")
		)
	)
	(footprint ""
		(layer "B.Cu")
		(at 84.84616 -388.011162 -90)
		(property "Reference" "C313"
			(at 0 0 90)
			(layer "B.SilkS")
			(hide yes)
			(effects
				(font
					(size 1.27 1.27)
				)
				(justify mirror)
			)
		)
		(property "Value" ""
			(at 0 0 90)
			(layer "B.Fab")
			(effects
				(font
					(size 1.27 1.27)
				)
				(justify mirror)
			)
		)
		(duplicate_pad_numbers_are_jumpers no)
		(fp_line
			(start -0.299974 0.150114)
			(end 0.299974 0.150114)
			(stroke
				(width 0.1)
				(type default)
			)
			(layer "B.Fab")
		)
		(fp_line
			(start 0.299974 0.150114)
			(end 0.299974 -0.150114)
			(stroke
				(width 0.1)
				(type default)
			)
			(layer "B.Fab")
		)
		(fp_line
			(start -0.299974 -0.150114)
			(end -0.299974 0.150114)
			(stroke
				(width 0.1)
				(type default)
			)
			(layer "B.Fab")
		)
		(fp_line
			(start 0.299974 -0.150114)
			(end -0.299974 -0.150114)
			(stroke
				(width 0.1)
				(type default)
			)
			(layer "B.Fab")
		)
		(pad "1" smd rect
			(at 0.2667 0 90)
			(size 0.3048 0.381)
			(layers "B.Cu" "B.Mask" "B.Paste")
			(net "P0V9_CPU1_RT1_2A_2D")
		)
		(pad "2" smd rect
			(at -0.2667 0 90)
			(size 0.3048 0.381)
			(layers "B.Cu" "B.Mask" "B.Paste")
			(net "GND")
		)
	)
	(footprint ""
		(layer "B.Cu")
		(at 366.217454 -268.41831)
		(property "Reference" "C2222"
			(at 0 0 0)
			(layer "B.SilkS")
			(hide yes)
			(effects
				(font
					(size 1.27 1.27)
				)
				(justify mirror)
			)
		)
		(property "Value" ""
			(at 0 0 0)
			(layer "B.Fab")
			(effects
				(font
					(size 1.27 1.27)
				)
				(justify mirror)
			)
		)
		(duplicate_pad_numbers_are_jumpers no)
		(fp_line
			(start -0.7874 -0.4064)
			(end -0.7874 0.4064)
			(stroke
				(width 0.1524)
				(type default)
			)
			(layer "B.SilkS")
		)
		(fp_line
			(start -0.7874 0.4064)
			(end 0.7874 0.4064)
			(stroke
				(width 0.1524)
				(type default)
			)
			(layer "B.SilkS")
		)
		(fp_line
			(start 0.7874 -0.4064)
			(end -0.7874 -0.4064)
			(stroke
				(width 0.1524)
				(type default)
			)
			(layer "B.SilkS")
		)
		(fp_line
			(start 0.7874 0.4064)
			(end 0.7874 -0.4064)
			(stroke
				(width 0.1524)
				(type default)
			)
			(layer "B.SilkS")
		)
		(fp_line
			(start -0.67945 -0.3048)
			(end -0.67945 0.3048)
			(stroke
				(width 0.1)
				(type default)
			)
			(layer "B.Fab")
		)
		(fp_line
			(start -0.67945 0.3048)
			(end -0.120396 0.3048)
			(stroke
				(width 0.1)
				(type default)
			)
			(layer "B.Fab")
		)
		(fp_line
			(start -0.12065 -0.3048)
			(end -0.67945 -0.3048)
			(stroke
				(width 0.1)
				(type default)
			)
			(layer "B.Fab")
		)
		(fp_line
			(start -0.12065 -0.2794)
			(end -0.12065 -0.3048)
			(stroke
				(width 0.1)
				(type default)
			)
			(layer "B.Fab")
		)
		(fp_line
			(start -0.120396 0.2794)
			(end 0.12065 0.2794)
			(stroke
				(width 0.1)
				(type default)
			)
			(layer "B.Fab")
		)
		(fp_line
			(start -0.120396 0.3048)
			(end -0.120396 0.2794)
			(stroke
				(width 0.1)
				(type default)
			)
			(layer "B.Fab")
		)
		(fp_line
			(start 0.12065 -0.305054)
			(end 0.12065 -0.2794)
			(stroke
				(width 0.1)
				(type default)
			)
			(layer "B.Fab")
		)
		(fp_line
			(start 0.12065 -0.2794)
			(end -0.12065 -0.2794)
			(stroke
				(width 0.1)
				(type default)
			)
			(layer "B.Fab")
		)
		(fp_line
			(start 0.12065 0.2794)
			(end 0.12065 0.3048)
			(stroke
				(width 0.1)
				(type default)
			)
			(layer "B.Fab")
		)
		(fp_line
			(start 0.12065 0.3048)
			(end 0.67945 0.3048)
			(stroke
				(width 0.1)
				(type default)
			)
			(layer "B.Fab")
		)
		(fp_line
			(start 0.67945 -0.305054)
			(end 0.12065 -0.305054)
			(stroke
				(width 0.1)
				(type default)
			)
			(layer "B.Fab")
		)
		(fp_line
			(start 0.67945 0.3048)
			(end 0.67945 -0.305054)
			(stroke
				(width 0.1)
				(type default)
			)
			(layer "B.Fab")
		)
		(pad "1" smd circle
			(at 0.40005 0 180)
			(size 0 0)
			(layers "B.Cu" "B.Mask" "B.Paste")
			(net "PVDDCR_CPU1_P0")
		)
		(pad "2" smd circle
			(at -0.40005 0 180)
			(size 0 0)
			(layers "B.Cu" "B.Mask" "B.Paste")
			(net "GND")
		)
	)
	(footprint ""
		(layer "B.Cu")
		(at 120.49125 -390.560052 90)
		(property "Reference" "C484"
			(at 0 0 90)
			(layer "B.SilkS")
			(hide yes)
			(effects
				(font
					(size 1.27 1.27)
				)
				(justify mirror)
			)
		)
		(property "Value" ""
			(at 0 0 90)
			(layer "B.Fab")
			(effects
				(font
					(size 1.27 1.27)
				)
				(justify mirror)
			)
		)
		(duplicate_pad_numbers_are_jumpers no)
		(fp_line
			(start 0.7874 -0.4064)
			(end -0.7874 -0.4064)
			(stroke
				(width 0.1524)
				(type default)
			)
			(layer "B.SilkS")
		)
		(fp_line
			(start -0.7874 -0.4064)
			(end -0.7874 0.4064)
			(stroke
				(width 0.1524)
				(type default)
			)
			(layer "B.SilkS")
		)
		(fp_line
			(start 0.7874 0.4064)
			(end 0.7874 -0.4064)
			(stroke
				(width 0.1524)
				(type default)
			)
			(layer "B.SilkS")
		)
		(fp_line
			(start -0.7874 0.4064)
			(end 0.7874 0.4064)
			(stroke
				(width 0.1524)
				(type default)
			)
			(layer "B.SilkS")
		)
		(fp_line
			(start 0.67945 -0.305054)
			(end 0.12065 -0.305054)
			(stroke
				(width 0.1)
				(type default)
			)
			(layer "B.Fab")
		)
		(fp_line
			(start 0.12065 -0.305054)
			(end 0.12065 -0.2794)
			(stroke
				(width 0.1)
				(type default)
			)
			(layer "B.Fab")
		)
		(fp_line
			(start -0.12065 -0.3048)
			(end -0.67945 -0.3048)
			(stroke
				(width 0.1)
				(type default)
			)
			(layer "B.Fab")
		)
		(fp_line
			(start -0.67945 -0.3048)
			(end -0.67945 0.3048)
			(stroke
				(width 0.1)
				(type default)
			)
			(layer "B.Fab")
		)
		(fp_line
			(start 0.12065 -0.2794)
			(end -0.12065 -0.2794)
			(stroke
				(width 0.1)
				(type default)
			)
			(layer "B.Fab")
		)
		(fp_line
			(start -0.12065 -0.2794)
			(end -0.12065 -0.3048)
			(stroke
				(width 0.1)
				(type default)
			)
			(layer "B.Fab")
		)
		(fp_line
			(start 0.12065 0.2794)
			(end 0.12065 0.3048)
			(stroke
				(width 0.1)
				(type default)
			)
			(layer "B.Fab")
		)
		(fp_line
			(start -0.120396 0.2794)
			(end 0.12065 0.2794)
			(stroke
				(width 0.1)
				(type default)
			)
			(layer "B.Fab")
		)
		(fp_line
			(start 0.67945 0.3048)
			(end 0.67945 -0.305054)
			(stroke
				(width 0.1)
				(type default)
			)
			(layer "B.Fab")
		)
		(fp_line
			(start 0.12065 0.3048)
			(end 0.67945 0.3048)
			(stroke
				(width 0.1)
				(type default)
			)
			(layer "B.Fab")
		)
		(fp_line
			(start -0.120396 0.3048)
			(end -0.120396 0.2794)
			(stroke
				(width 0.1)
				(type default)
			)
			(layer "B.Fab")
		)
		(fp_line
			(start -0.67945 0.3048)
			(end -0.120396 0.3048)
			(stroke
				(width 0.1)
				(type default)
			)
			(layer "B.Fab")
		)
		(pad "1" smd circle
			(at 0.40005 0 270)
			(size 0 0)
			(layers "B.Cu" "B.Mask" "B.Paste")
			(net "P0V9_CPU1_RT_2D")
		)
		(pad "2" smd circle
			(at -0.40005 0 270)
			(size 0 0)
			(layers "B.Cu" "B.Mask" "B.Paste")
			(net "GND")
		)
	)
)
